# T6G (Grand Teton) — schematic netlist excerpt (pin names and nets, part order shuffled) for the footprints in the layout excerpt that follows; sources: Cadence DE-HDL packaged netlist, KiCad conversion of 04192023_DAF0TMB3IC0_F0TG_MB_C_brd_V02_OCP.brd

R8042  Q_RES  1K 1% EMPTY  pkg 0402LF  page 200 : A = SVID_PVDDCR_CPU1_P0_SVTO ; B = GND
R145  Q_RES  0 5% EMPTY  pkg 0402LF  page 161 : A = SMB_CPU0_CPU1_SEC_SCL_R2 ; B = SMB_CPU0_SEC_R_SCL
PC329_1  Q_CAP  22UF 16V 20% X6S  pkg C0805  page 215 : A = SW_P12V_AUX_PVDDCR_SOC_P1_FLT ; B = GND

(kicad_pcb
	(version 20260206)
	(generator "pcbnew")
	(generator_version "10.0")
	(general
		(thickness 1.6)
		(legacy_teardrops no)
	)
	(paper "A4")
	(title_block
		(title "04192023_DAF0TMB3IC0_F0TG_MB_C_brd_V02_OCP.brd")
		(comment 1 "Grand Teton / footprints 5290-5292 of 8354")
	)
	(layers
		(0 "F.Cu" signal "TOP")
		(4 "In1.Cu" signal "GND")
		(6 "In2.Cu" signal "IN1")
		(8 "In3.Cu" signal "GND1")
		(10 "In4.Cu" signal "IN2")
		(12 "In5.Cu" signal "GND2")
		(14 "In6.Cu" signal "IN3")
		(16 "In7.Cu" signal "GND3")
		(18 "In8.Cu" signal "VCC")
		(20 "In9.Cu" signal "VCC1")
		(22 "In10.Cu" signal "GND4")
		(24 "In11.Cu" signal "IN4")
		(26 "In12.Cu" signal "GND5")
		(28 "In13.Cu" signal "IN5")
		(30 "In14.Cu" signal "GND6")
		(32 "In15.Cu" signal "IN6")
		(34 "In16.Cu" signal "GND7")
		(2 "B.Cu" signal "BOTTOM")
		(9 "F.Adhes" user "F.Adhesive")
		(11 "B.Adhes" user "B.Adhesive")
		(13 "F.Paste" user "Package Geometry/Pastemask Top")
		(15 "B.Paste" user "Package Geometry/Pastemask Bottom")
		(5 "F.SilkS" user "Ref Des/Silkscreen Top")
		(7 "B.SilkS" user "Ref Des/Silkscreen Bottom")
		(1 "F.Mask" user "Board Geometry/Soldermask Top")
		(3 "B.Mask" user "Board Geometry/Soldermask Bottom")
		(17 "Dwgs.User" user "User.Drawings")
		(19 "Cmts.User" user "User.Comments")
		(21 "Eco1.User" user "User.Eco1")
		(23 "Eco2.User" user "User.Eco2")
		(25 "Edge.Cuts" user "Board Geometry/Outline")
		(27 "Margin" user)
		(31 "F.CrtYd" user "Package Geometry/Place Bound Top")
		(29 "B.CrtYd" user "Package Geometry/Place Bound Bottom")
		(35 "F.Fab" user "Ref Des/Assembly Top")
		(33 "B.Fab" user "Ref Des/Assembly Bottom")
	)
	(footprint ""
		(layer "B.Cu")
		(at 241.427 -234.061 -90)
		(property "Reference" "R145"
			(at 0 0 90)
			(layer "B.SilkS")
			(hide yes)
			(effects
				(font
					(size 1.27 1.27)
				)
				(justify mirror)
			)
		)
		(property "Value" ""
			(at 0 0 90)
			(layer "B.Fab")
			(effects
				(font
					(size 1.27 1.27)
				)
				(justify mirror)
			)
		)
		(duplicate_pad_numbers_are_jumpers no)
		(fp_line
			(start -0.7874 0.4064)
			(end 0.7874 0.4064)
			(stroke
				(width 0.1524)
				(type default)
			)
			(layer "B.SilkS")
		)
		(fp_line
			(start 0.7874 0.4064)
			(end 0.7874 -0.4064)
			(stroke
				(width 0.1524)
				(type default)
			)
			(layer "B.SilkS")
		)
		(fp_line
			(start -0.7874 -0.4064)
			(end -0.7874 0.4064)
			(stroke
				(width 0.1524)
				(type default)
			)
			(layer "B.SilkS")
		)
		(fp_line
			(start 0.7874 -0.4064)
			(end -0.7874 -0.4064)
			(stroke
				(width 0.1524)
				(type default)
			)
			(layer "B.SilkS")
		)
		(fp_line
			(start -0.67945 0.3048)
			(end -0.120396 0.3048)
			(stroke
				(width 0.1)
				(type default)
			)
			(layer "B.Fab")
		)
		(fp_line
			(start -0.120396 0.3048)
			(end -0.120396 0.2794)
			(stroke
				(width 0.1)
				(type default)
			)
			(layer "B.Fab")
		)
		(fp_line
			(start 0.12065 0.3048)
			(end 0.67945 0.3048)
			(stroke
				(width 0.1)
				(type default)
			)
			(layer "B.Fab")
		)
		(fp_line
			(start 0.67945 0.3048)
			(end 0.67945 -0.305054)
			(stroke
				(width 0.1)
				(type default)
			)
			(layer "B.Fab")
		)
		(fp_line
			(start -0.120396 0.2794)
			(end 0.12065 0.2794)
			(stroke
				(width 0.1)
				(type default)
			)
			(layer "B.Fab")
		)
		(fp_line
			(start 0.12065 0.2794)
			(end 0.12065 0.3048)
			(stroke
				(width 0.1)
				(type default)
			)
			(layer "B.Fab")
		)
		(fp_line
			(start -0.12065 -0.2794)
			(end -0.12065 -0.3048)
			(stroke
				(width 0.1)
				(type default)
			)
			(layer "B.Fab")
		)
		(fp_line
			(start 0.12065 -0.2794)
			(end -0.12065 -0.2794)
			(stroke
				(width 0.1)
				(type default)
			)
			(layer "B.Fab")
		)
		(fp_line
			(start -0.67945 -0.3048)
			(end -0.67945 0.3048)
			(stroke
				(width 0.1)
				(type default)
			)
			(layer "B.Fab")
		)
		(fp_line
			(start -0.12065 -0.3048)
			(end -0.67945 -0.3048)
			(stroke
				(width 0.1)
				(type default)
			)
			(layer "B.Fab")
		)
		(fp_line
			(start 0.12065 -0.305054)
			(end 0.12065 -0.2794)
			(stroke
				(width 0.1)
				(type default)
			)
			(layer "B.Fab")
		)
		(fp_line
			(start 0.67945 -0.305054)
			(end 0.12065 -0.305054)
			(stroke
				(width 0.1)
				(type default)
			)
			(layer "B.Fab")
		)
		(pad "1" smd circle
			(at 0.40005 0 90)
			(size 0 0)
			(layers "B.Cu" "B.Mask" "B.Paste")
			(net "SMB_CPU0_CPU1_SEC_SCL_R2")
		)
		(pad "2" smd circle
			(at -0.40005 0 90)
			(size 0 0)
			(layers "B.Cu" "B.Mask" "B.Paste")
			(net "SMB_CPU0_SEC_R_SCL")
		)
	)
	(footprint ""
		(layer "B.Cu")
		(at 304.419 -355.854 180)
		(property "Reference" "R8042"
			(at 0 0 0)
			(layer "B.SilkS")
			(hide yes)
			(effects
				(font
					(size 1.27 1.27)
				)
				(justify mirror)
			)
		)
		(property "Value" ""
			(at 0 0 0)
			(layer "B.Fab")
			(effects
				(font
					(size 1.27 1.27)
				)
				(justify mirror)
			)
		)
		(duplicate_pad_numbers_are_jumpers no)
		(fp_line
			(start 0.7874 0.4064)
			(end 0.7874 -0.4064)
			(stroke
				(width 0.1524)
				(type default)
			)
			(layer "B.SilkS")
		)
		(fp_line
			(start 0.7874 -0.4064)
			(end -0.7874 -0.4064)
			(stroke
				(width 0.1524)
				(type default)
			)
			(layer "B.SilkS")
		)
		(fp_line
			(start -0.7874 0.4064)
			(end 0.7874 0.4064)
			(stroke
				(width 0.1524)
				(type default)
			)
			(layer "B.SilkS")
		)
		(fp_line
			(start -0.7874 -0.4064)
			(end -0.7874 0.4064)
			(stroke
				(width 0.1524)
				(type default)
			)
			(layer "B.SilkS")
		)
		(fp_line
			(start 0.67945 0.3048)
			(end 0.67945 -0.305054)
			(stroke
				(width 0.1)
				(type default)
			)
			(layer "B.Fab")
		)
		(fp_line
			(start 0.67945 -0.305054)
			(end 0.12065 -0.305054)
			(stroke
				(width 0.1)
				(type default)
			)
			(layer "B.Fab")
		)
		(fp_line
			(start 0.12065 0.3048)
			(end 0.67945 0.3048)
			(stroke
				(width 0.1)
				(type default)
			)
			(layer "B.Fab")
		)
		(fp_line
			(start 0.12065 0.2794)
			(end 0.12065 0.3048)
			(stroke
				(width 0.1)
				(type default)
			)
			(layer "B.Fab")
		)
		(fp_line
			(start 0.12065 -0.2794)
			(end -0.12065 -0.2794)
			(stroke
				(width 0.1)
				(type default)
			)
			(layer "B.Fab")
		)
		(fp_line
			(start 0.12065 -0.305054)
			(end 0.12065 -0.2794)
			(stroke
				(width 0.1)
				(type default)
			)
			(layer "B.Fab")
		)
		(fp_line
			(start -0.120396 0.3048)
			(end -0.120396 0.2794)
			(stroke
				(width 0.1)
				(type default)
			)
			(layer "B.Fab")
		)
		(fp_line
			(start -0.120396 0.2794)
			(end 0.12065 0.2794)
			(stroke
				(width 0.1)
				(type default)
			)
			(layer "B.Fab")
		)
		(fp_line
			(start -0.12065 -0.2794)
			(end -0.12065 -0.3048)
			(stroke
				(width 0.1)
				(type default)
			)
			(layer "B.Fab")
		)
		(fp_line
			(start -0.12065 -0.3048)
			(end -0.67945 -0.3048)
			(stroke
				(width 0.1)
				(type default)
			)
			(layer "B.Fab")
		)
		(fp_line
			(start -0.67945 0.3048)
			(end -0.120396 0.3048)
			(stroke
				(width 0.1)
				(type default)
			)
			(layer "B.Fab")
		)
		(fp_line
			(start -0.67945 -0.3048)
			(end -0.67945 0.3048)
			(stroke
				(width 0.1)
				(type default)
			)
			(layer "B.Fab")
		)
		(pad "1" smd circle
			(at 0.40005 0)
			(size 0 0)
			(layers "B.Cu" "B.Mask" "B.Paste")
			(net "SVID_PVDDCR_CPU1_P0_SVTO")
		)
		(pad "2" smd circle
			(at -0.40005 0)
			(size 0 0)
			(layers "B.Cu" "B.Mask" "B.Paste")
			(net "GND")
		)
	)
	(footprint ""
		(layer "B.Cu")
		(at 114.607848 -171.785534 -90)
		(property "Reference" "PC329_1"
			(at 0 0 90)
			(layer "B.SilkS")
			(hide yes)
			(effects
				(font
					(size 1.27 1.27)
				)
				(justify mirror)
			)
		)
		(property "Value" ""
			(at 0 0 90)
			(layer "B.Fab")
			(effects
				(font
					(size 1.27 1.27)
				)
				(justify mirror)
			)
		)
		(duplicate_pad_numbers_are_jumpers no)
		(fp_line
			(start -1.524 0.762)
			(end 1.524 0.762)
			(stroke
				(width 0.1524)
				(type default)
			)
			(layer "B.SilkS")
		)
		(fp_line
			(start 1.524 0.762)
			(end 1.524 -0.762)
			(stroke
				(width 0.1524)
				(type default)
			)
			(layer "B.SilkS")
		)
		(fp_line
			(start -1.524 -0.762)
			(end -1.524 0.762)
			(stroke
				(width 0.1524)
				(type default)
			)
			(layer "B.SilkS")
		)
		(fp_line
			(start 1.524 -0.762)
			(end -1.524 -0.762)
			(stroke
				(width 0.1524)
				(type default)
			)
			(layer "B.SilkS")
		)
		(fp_line
			(start -1.1049 0.724916)
			(end -1.1049 -0.724916)
			(stroke
				(width 0.1)
				(type default)
			)
			(layer "B.Fab")
		)
		(fp_line
			(start 1.1049 0.724916)
			(end -1.1049 0.724916)
			(stroke
				(width 0.1)
				(type default)
			)
			(layer "B.Fab")
		)
		(fp_line
			(start -1.1049 -0.724916)
			(end 1.1049 -0.724916)
			(stroke
				(width 0.1)
				(type default)
			)
			(layer "B.Fab")
		)
		(fp_line
			(start 1.1049 -0.724916)
			(end 1.1049 0.724916)
			(stroke
				(width 0.1)
				(type default)
			)
			(layer "B.Fab")
		)
		(pad "1" smd rect
			(at 0.889 0 270)
			(size 1.016 1.27)
			(layers "B.Cu" "B.Mask" "B.Paste")
			(net "SW_P12V_AUX_PVDDCR_SOC_P1_FLT")
		)
		(pad "2" smd rect
			(at -0.889 0 270)
			(size 1.016 1.27)
			(layers "B.Cu" "B.Mask" "B.Paste")
			(net "GND")
		)
	)
)
